#  M.2 to OCuLink adapter — KiCad project settings (.kicad_pro: net classes, design rules, text variables)
{
  "board": {
    "3dviewports": [],
    "design_settings": {
      "defaults": {
        "apply_defaults_to_fp_fields": false,
        "apply_defaults_to_fp_shapes": false,
        "apply_defaults_to_fp_text": false,
        "board_outline_line_width": 0.05,
        "copper_line_width": 0.2,
        "copper_text_italic": false,
        "copper_text_size_h": 1.5,
        "copper_text_size_v": 1.5,
        "copper_text_thickness": 0.3,
        "copper_text_upright": false,
        "courtyard_line_width": 0.05,
        "dimension_precision": 4,
        "dimension_units": 3,
        "dimensions": {
          "arrow_length": 1270000,
          "extension_offset": 500000,
          "keep_text_aligned": true,
          "suppress_zeroes": true,
          "text_position": 0,
          "units_format": 0
        },
        "fab_line_width": 0.1,
        "fab_text_italic": false,
        "fab_text_size_h": 1.0,
        "fab_text_size_v": 1.0,
        "fab_text_thickness": 0.15,
        "fab_text_upright": false,
        "other_line_width": 0.1,
        "other_text_italic": false,
        "other_text_size_h": 1.0,
        "other_text_size_v": 1.0,
        "other_text_thickness": 0.15,
        "other_text_upright": false,
        "pads": {
          "drill": 0.0,
          "height": 0.4,
          "width": 0.46
        },
        "silk_line_width": 0.1,
        "silk_text_italic": false,
        "silk_text_size_h": 1.0,
        "silk_text_size_v": 1.0,
        "silk_text_thickness": 0.1,
        "silk_text_upright": false,
        "zones": {
          "min_clearance": 0.2
        }
      },
      "diff_pair_dimensions": [
        {
          "gap": 0.0,
          "via_gap": 0.0,
          "width": 0.0
        },
        {
          "gap": 0.11,
          "via_gap": 0.111,
          "width": 0.22
        }
      ],
      "drc_exclusions": [],
      "meta": {
        "version": 2
      },
      "rule_severities": {
        "annular_width": "error",
        "clearance": "error",
        "connection_width": "warning",
        "copper_edge_clearance": "error",
        "copper_sliver": "warning",
        "courtyards_overlap": "error",
        "creepage": "error",
        "diff_pair_gap_out_of_range": "error",
        "diff_pair_uncoupled_length_too_long": "error",
        "drill_out_of_range": "error",
        "duplicate_footprints": "warning",
        "extra_footprint": "warning",
        "footprint": "error",
        "footprint_filters_mismatch": "error",
        "footprint_symbol_mismatch": "warning",
        "footprint_type_mismatch": "error",
        "hole_clearance": "error",
        "hole_to_hole": "error",
        "holes_co_located": "error",
        "invalid_outline": "error",
        "isolated_copper": "warning",
        "item_on_disabled_layer": "error",
        "items_not_allowed": "error",
        "length_out_of_range": "error",
        "lib_footprint_issues": "ignore",
        "lib_footprint_mismatch": "error",
        "malformed_courtyard": "error",
        "microvia_drill_out_of_range": "error",
        "mirrored_text_on_front_layer": "warning",
        "missing_courtyard": "error",
        "missing_footprint": "warning",
        "net_conflict": "warning",
        "nonmirrored_text_on_back_layer": "warning",
        "npth_inside_courtyard": "warning",
        "padstack": "error",
        "pth_inside_courtyard": "warning",
        "shorting_items": "error",
        "silk_edge_clearance": "warning",
        "silk_over_copper": "warning",
        "silk_overlap": "warning",
        "skew_out_of_range": "error",
        "solder_mask_bridge": "error",
        "starved_thermal": "error",
        "text_height": "warning",
        "text_on_edge_cuts": "error",
        "text_thickness": "warning",
        "through_hole_pad_without_hole": "error",
        "too_many_vias": "error",
        "track_angle": "error",
        "track_dangling": "warning",
        "track_segment_length": "error",
        "track_width": "error",
        "tracks_crossing": "error",
        "unconnected_items": "error",
        "unresolved_variable": "error",
        "via_dangling": "warning",
        "zones_intersect": "error"
      },
      "rules": {
        "max_error": 0.005,
        "min_clearance": 0.1,
        "min_connection": 0.0,
        "min_copper_edge_clearance": 0.2,
        "min_groove_width": 0.0,
        "min_hole_clearance": 0.125,
        "min_hole_to_hole": 0.25,
        "min_microvia_diameter": 0.2,
        "min_microvia_drill": 0.1,
        "min_resolved_spokes": 1,
        "min_silk_clearance": 0.0,
        "min_text_height": 0.65,
        "min_text_thickness": 0.08,
        "min_through_hole_diameter": 0.1,
        "min_track_width": 0.125,
        "min_via_annular_width": 0.15,
        "min_via_diameter": 0.5,
        "solder_mask_to_copper_clearance": 0.0,
        "use_height_for_length_calcs": true
      },
      "teardrop_options": [
        {
          "td_onpthpad": true,
          "td_onroundshapesonly": false,
          "td_onsmdpad": true,
          "td_ontrackend": true,
          "td_onvia": true
        }
      ],
      "teardrop_parameters": [
        {
          "td_allow_use_two_tracks": true,
          "td_curve_segcount": 0,
          "td_height_ratio": 1.0,
          "td_length_ratio": 0.5,
          "td_maxheight": 2.0,
          "td_maxlen": 1.0,
          "td_on_pad_in_zone": false,
          "td_target_name": "td_round_shape",
          "td_width_to_size_filter_ratio": 0.9
        },
        {
          "td_allow_use_two_tracks": true,
          "td_curve_segcount": 0,
          "td_height_ratio": 1.0,
          "td_length_ratio": 0.5,
          "td_maxheight": 2.0,
          "td_maxlen": 1.0,
          "td_on_pad_in_zone": false,
          "td_target_name": "td_rect_shape",
          "td_width_to_size_filter_ratio": 0.9
        },
        {
          "td_allow_use_two_tracks": true,
          "td_curve_segcount": 0,
          "td_height_ratio": 1.0,
          "td_length_ratio": 0.5,
          "td_maxheight": 2.0,
          "td_maxlen": 1.0,
          "td_on_pad_in_zone": false,
          "td_target_name": "td_track_end",
          "td_width_to_size_filter_ratio": 0.9
        }
      ],
      "track_widths": [
        0.0,
        0.125,
        0.2,
        0.25,
        0.4
      ],
      "tuning_pattern_settings": {
        "diff_pair_defaults": {
          "corner_radius_percentage": 80,
          "corner_style": 1,
          "max_amplitude": 1.0,
          "min_amplitude": 0.2,
          "single_sided": false,
          "spacing": 1.0
        },
        "diff_pair_skew_defaults": {
          "corner_radius_percentage": 80,
          "corner_style": 1,
          "max_amplitude": 0.5,
          "min_amplitude": 0.2,
          "single_sided": false,
          "spacing": 0.5
        },
        "single_track_defaults": {
          "corner_radius_percentage": 80,
          "corner_style": 1,
          "max_amplitude": 1.0,
          "min_amplitude": 0.2,
          "single_sided": false,
          "spacing": 0.6
        }
      },
      "via_dimensions": [
        {
          "diameter": 0.0,
          "drill": 0.0
        },
        {
          "diameter": 0.5,
          "drill": 0.2
        }
      ],
      "zones_allow_external_fillets": false
    },
    "ipc2581": {
      "dist": "",
      "distpn": "",
      "internal_id": "",
      "mfg": "",
      "mpn": ""
    },
    "layer_pairs": [],
    "layer_presets": [],
    "viewports": []
  },
  "boards": [],
  "cvpcb": {
    "equivalence_files": []
  },
  "erc": {
    "erc_exclusions": [],
    "meta": {
      "version": 0
    },
    "pin_map": [
      [
        0,
        0,
        0,
        0,
        0,
        0,
        1,
        0,
        0,
        0,
        0,
        2
      ],
      [
        0,
        2,
        0,
        1,
        0,
        0,
        1,
        0,
        2,
        2,
        2,
        2
      ],
      [
        0,
        0,
        0,
        0,
        0,
        0,
        1,
        0,
        1,
        0,
        1,
        2
      ],
      [
        0,
        1,
        0,
        0,
        0,
        0,
        1,
        1,
        2,
        1,
        1,
        2
      ],
      [
        0,
        0,
        0,
        0,
        0,
        0,
        1,
        0,
        0,
        0,
        0,
        2
      ],
      [
        0,
        0,
        0,
        0,
        0,
        0,
        0,
        0,
        0,
        0,
        0,
        2
      ],
      [
        1,
        1,
        1,
        1,
        1,
        0,
        1,
        1,
        1,
        1,
        1,
        2
      ],
      [
        0,
        0,
        0,
        1,
        0,
        0,
        1,
        0,
        0,
        0,
        0,
        2
      ],
      [
        0,
        2,
        1,
        2,
        0,
        0,
        1,
        0,
        2,
        2,
        2,
        2
      ],
      [
        0,
        2,
        0,
        1,
        0,
        0,
        1,
        0,
        2,
        0,
        0,
        2
      ],
      [
        0,
        2,
        1,
        1,
        0,
        0,
        1,
        0,
        2,
        0,
        0,
        2
      ],
      [
        2,
        2,
        2,
        2,
        2,
        2,
        2,
        2,
        2,
        2,
        2,
        2
      ]
    ],
    "rule_severities": {
      "bus_definition_conflict": "error",
      "bus_entry_needed": "error",
      "bus_to_bus_conflict": "error",
      "bus_to_net_conflict": "error",
      "different_unit_footprint": "error",
      "different_unit_net": "error",
      "duplicate_reference": "error",
      "duplicate_sheet_names": "error",
      "endpoint_off_grid": "warning",
      "extra_units": "error",
      "footprint_filter": "ignore",
      "footprint_link_issues": "warning",
      "four_way_junction": "ignore",
      "global_label_dangling": "warning",
      "hier_label_mismatch": "error",
      "label_dangling": "error",
      "label_multiple_wires": "warning",
      "lib_symbol_issues": "warning",
      "lib_symbol_mismatch": "warning",
      "missing_bidi_pin": "warning",
      "missing_input_pin": "warning",
      "missing_power_pin": "error",
      "missing_unit": "warning",
      "multiple_net_names": "warning",
      "net_not_bus_member": "warning",
      "no_connect_connected": "warning",
      "no_connect_dangling": "warning",
      "pin_not_connected": "error",
      "pin_not_driven": "error",
      "pin_to_pin": "error",
      "power_pin_not_driven": "error",
      "same_local_global_label": "warning",
      "similar_label_and_power": "warning",
      "similar_labels": "warning",
      "similar_power": "warning",
      "simulation_model_issue": "ignore",
      "single_global_label": "ignore",
      "unannotated": "error",
      "unconnected_wire_endpoint": "warning",
      "unit_value_mismatch": "error",
      "unresolved_variable": "error",
      "wire_dangling": "error"
    }
  },
  "libraries": {
    "pinned_footprint_libs": [],
    "pinned_symbol_libs": []
  },
  "meta": {
    "filename": "antmicro-m2-oculink-adapter-hw.kicad_pro",
    "version": 3
  },
  "net_settings": {
    "classes": [
      {
        "bus_width": 12,
        "clearance": 0.125,
        "diff_pair_gap": 0.25,
        "diff_pair_via_gap": 0.25,
        "diff_pair_width": 0.2,
        "line_style": 0,
        "microvia_diameter": 0.3,
        "microvia_drill": 0.1,
        "name": "Default",
        "pcb_color": "rgba(0, 0, 0, 0.000)",
        "priority": 2147483647,
        "schematic_color": "rgba(0, 0, 0, 0.000)",
        "track_width": 0.2,
        "via_diameter": 0.5,
        "via_drill": 0.2,
        "wire_width": 6
      },
      {
        "bus_width": 12,
        "clearance": 0.11,
        "diff_pair_gap": 0.11,
        "diff_pair_width": 0.22,
        "line_style": 0,
        "microvia_diameter": 0.45,
        "microvia_drill": 0.1,
        "name": "85Ohm-diff_PCIE",
        "pcb_color": "rgba(0, 0, 0, 0.000)",
        "priority": 0,
        "schematic_color": "rgba(0, 0, 0, 0.000)",
        "track_width": 0.22,
        "via_diameter": 0.5,
        "via_drill": 0.2,
        "wire_width": 6
      }
    ],
    "meta": {
      "version": 4
    },
    "net_colors": null,
    "netclass_assignments": null,
    "netclass_patterns": [
      {
        "netclass": "85Ohm-diff_PCIE",
        "pattern": "*PCIe_*"
      }
    ]
  },
  "pcbnew": {
    "last_paths": {
      "gencad": "",
      "idf": "",
      "netlist": "",
      "plot": "",
      "pos_files": "",
      "specctra_dsn": "",
      "step": "",
      "svg": "",
      "vrml": ""
    },
    "page_layout_descr_file": ""
  },
  "schematic": {
    "annotate_start_num": 0,
    "bom_export_filename": "${PROJECTNAME}.csv",
    "bom_fmt_presets": [],
    "bom_fmt_settings": {
      "field_delimiter": ",",
      "keep_line_breaks": false,
      "keep_tabs": false,
      "name": "CSV",
      "ref_delimiter": ",",
      "ref_range_delimiter": "",
      "string_delimiter": "\""
    },
    "bom_presets": [],
    "bom_settings": {
      "exclude_dnp": false,
      "fields_ordered": [
        {
          "group_by": false,
          "label": "Reference",
          "name": "Reference",
          "show": true
        },
        {
          "group_by": false,
          "label": "Qty",
          "name": "${QUANTITY}",
          "show": true
        },
        {
          "group_by": true,
          "label": "Value",
          "name": "Value",
          "show": true
        },
        {
          "group_by": true,
          "label": "DNP",
          "name": "${DNP}",
          "show": true
        },
        {
          "group_by": true,
          "label": "Exclude from BOM",
          "name": "${EXCLUDE_FROM_BOM}",
          "show": true
        },
        {
          "group_by": true,
          "label": "Exclude from Board",
          "name": "${EXCLUDE_FROM_BOARD}",
          "show": true
        },
        {
          "group_by": true,
          "label": "Footprint",
          "name": "Footprint",
          "show": true
        },
        {
          "group_by": false,
          "label": "Datasheet",
          "name": "Datasheet",
          "show": true
        }
      ],
      "filter_string": "",
      "group_symbols": true,
      "include_excluded_from_bom": true,
      "name": "Default Editing",
      "sort_asc": true,
      "sort_field": "Reference"
    },
    "connection_grid_size": 50.0,
    "drawing": {
      "dashed_lines_dash_length_ratio": 12.0,
      "dashed_lines_gap_length_ratio": 3.0,
      "default_line_thickness": 6.0,
      "default_text_size": 50.0,
      "field_names": [],
      "intersheets_ref_own_page": false,
      "intersheets_ref_prefix": "",
      "intersheets_ref_short": false,
      "intersheets_ref_show": false,
      "intersheets_ref_suffix": "",
      "junction_size_choice": 3,
      "label_size_ratio": 0.375,
      "operating_point_overlay_i_precision": 3,
      "operating_point_overlay_i_range": "~A",
      "operating_point_overlay_v_precision": 3,
      "operating_point_overlay_v_range": "~V",
      "overbar_offset_ratio": 1.23,
      "pin_symbol_size": 25.0,
      "text_offset_ratio": 0.15
    },
    "legacy_lib_dir": "",
    "legacy_lib_list": [],
    "meta": {
      "version": 1
    },
    "net_format_name": "",
    "page_layout_descr_file": "",
    "plot_directory": "/home/<user>/projects/hw/antmicro-m2-oculink-adapter-hw/",
    "space_save_all_events": true,
    "spice_current_sheet_as_root": false,
    "spice_external_command": "spice \"%I\"",
    "spice_model_current_sheet_as_root": true,
    "spice_save_all_currents": false,
    "spice_save_all_dissipations": false,
    "spice_save_all_voltages": false,
    "subpart_first_id": 65,
    "subpart_id_separator": 0
  },
  "sheets": [
    [
      "",
      "Root"
    ]
  ],
  "text_variables": {}
}
